(kicad_pcb
	(version 20260206)
	(generator "pcbnew")
	(generator_version "10.0")
	(general
		(thickness 1.6)
		(legacy_teardrops no)
	)
	(paper "A4")
	(title_block
		(title "Bryce Canyon_F.DPB_16315-1-OCP.brd")
		(comment 1 "Bryce Canyon / footprints 106-112 of 2223")
	)
	(layers
		(0 "F.Cu" signal "TOP")
		(4 "In1.Cu" signal "L2GND")
		(6 "In2.Cu" signal "L3")
		(8 "In3.Cu" signal "L4GND")
		(10 "In4.Cu" signal "L5")
		(12 "In5.Cu" signal "L6VCC")
		(14 "In6.Cu" signal "L7VCC")
		(16 "In7.Cu" signal "L8")
		(18 "In8.Cu" signal "L9GND")
		(20 "In9.Cu" signal "L10")
		(22 "In10.Cu" signal "L11GND")
		(2 "B.Cu" signal "BOTTOM")
		(9 "F.Adhes" user "F.Adhesive")
		(11 "B.Adhes" user "B.Adhesive")
		(13 "F.Paste" user "Package Geometry/Pastemask Top")
		(15 "B.Paste" user "Package Geometry/Pastemask Bottom")
		(5 "F.SilkS" user "Ref Des/Silkscreen Top")
		(7 "B.SilkS" user "Ref Des/Silkscreen Bottom")
		(1 "F.Mask" user "Board Geometry/Soldermask Top")
		(3 "B.Mask" user "Board Geometry/Soldermask Bottom")
		(17 "Dwgs.User" user "User.Drawings")
		(19 "Cmts.User" user "User.Comments")
		(21 "Eco1.User" user "User.Eco1")
		(23 "Eco2.User" user "User.Eco2")
		(25 "Edge.Cuts" user "Board Geometry/Outline")
		(27 "Margin" user)
		(31 "F.CrtYd" user "Package Geometry/Place Bound Top")
		(29 "B.CrtYd" user "Package Geometry/Place Bound Bottom")
		(35 "F.Fab" user "Ref Des/Assembly Top")
		(33 "B.Fab" user "Ref Des/Assembly Bottom")
	)
	(footprint ""
		(layer "F.Cu")
		(at 255.0922 -290.195)
		(property "Reference" "R2"
			(at 0 0 0)
			(layer "F.SilkS")
			(hide yes)
			(effects
				(font
					(size 1.27 1.27)
				)
			)
		)
		(property "Value" "4K7R2F-GP"
			(at 0.064008 -3.993896 0)
			(unlocked yes)
			(layer "F.Fab")
			(hide yes)
			(effects
				(font
					(size 1.016 1.016)
					(thickness 0.1524)
				)
			)
		)
		(property "Device Type" "R402H16"
			(at 0.064008 -5.517896 0)
			(unlocked yes)
			(layer "F.Fab")
			(hide yes)
			(effects
				(font
					(size 1.016 1.016)
					(thickness 0.1524)
				)
			)
		)
		(duplicate_pad_numbers_are_jumpers no)
		(fp_line
			(start -0.508 -0.9398)
			(end -0.508 0.9398)
			(stroke
				(width 0.1524)
				(type default)
			)
			(layer "F.SilkS")
		)
		(fp_line
			(start 0.508 -0.9398)
			(end -0.508 -0.9398)
			(stroke
				(width 0.1524)
				(type default)
			)
			(layer "F.SilkS")
		)
		(fp_rect
			(start -0.508 0.9398)
			(end 0.508 -0.9398)
			(stroke
				(width 0)
				(type default)
			)
			(fill no)
			(layer "F.CrtYd")
		)
		(fp_rect
			(start -0.508 0.9398)
			(end 0.508 -0.9398)
			(stroke
				(width 0)
				(type default)
			)
			(fill no)
			(layer "F.Fab")
		)
		(pad "1" smd custom
			(at 0 -0.4445)
			(size 0.1397 0.1397)
			(layers "F.Cu" "F.Mask" "F.Paste")
			(net "EEPROM_A1")
			(options
				(clearance outline)
				(anchor circle)
			)
			(primitives
				(gr_poly
					(pts
						(arc
							(start -0.1778 -0.2794)
							(mid -0.249642 -0.249642)
							(end -0.2794 -0.1778)
						)
						(arc
							(start -0.2794 0.1778)
							(mid -0.249642 0.249642)
							(end -0.1778 0.2794)
						)
						(arc
							(start 0.1778 0.2794)
							(mid 0.249642 0.249642)
							(end 0.2794 0.1778)
						)
						(arc
							(start 0.2794 -0.1778)
							(mid 0.249642 -0.249642)
							(end 0.1778 -0.2794)
						)
					)
					(width 0)
					(fill yes)
				)
			)
		)
		(pad "2" smd custom
			(at 0 0.4445)
			(size 0.1397 0.1397)
			(layers "F.Cu" "F.Mask" "F.Paste")
			(net "GND")
			(options
				(clearance outline)
				(anchor circle)
			)
			(primitives
				(gr_poly
					(pts
						(arc
							(start -0.1778 -0.2794)
							(mid -0.249642 -0.249642)
							(end -0.2794 -0.1778)
						)
						(arc
							(start -0.2794 0.1778)
							(mid -0.249642 0.249642)
							(end -0.1778 0.2794)
						)
						(arc
							(start 0.1778 0.2794)
							(mid 0.249642 0.249642)
							(end 0.2794 0.1778)
						)
						(arc
							(start 0.2794 -0.1778)
							(mid 0.249642 -0.249642)
							(end 0.1778 -0.2794)
						)
					)
					(width 0)
					(fill yes)
				)
			)
		)
	)
	(footprint ""
		(layer "F.Cu")
		(at 371.62359 -128.24079 180)
		(property "Reference" "R534"
			(at 0 0 180)
			(layer "F.SilkS")
			(hide yes)
			(effects
				(font
					(size 1.27 1.27)
				)
			)
		)
		(property "Value" "4K7R2J-2-GP"
			(at 0.064008 -3.993896 180)
			(unlocked yes)
			(layer "F.Fab")
			(hide yes)
			(effects
				(font
					(size 1.016 1.016)
					(thickness 0.1524)
				)
			)
		)
		(property "Device Type" "R402H16"
			(at 0.064008 -5.517896 180)
			(unlocked yes)
			(layer "F.Fab")
			(hide yes)
			(effects
				(font
					(size 1.016 1.016)
					(thickness 0.1524)
				)
			)
		)
		(duplicate_pad_numbers_are_jumpers no)
		(fp_line
			(start 0.508 -0.9398)
			(end -0.508 -0.9398)
			(stroke
				(width 0.1524)
				(type default)
			)
			(layer "F.SilkS")
		)
		(fp_line
			(start -0.508 -0.9398)
			(end -0.508 0.9398)
			(stroke
				(width 0.1524)
				(type default)
			)
			(layer "F.SilkS")
		)
		(fp_rect
			(start -0.508 0.9398)
			(end 0.508 -0.9398)
			(stroke
				(width 0)
				(type default)
			)
			(fill no)
			(layer "F.CrtYd")
		)
		(fp_rect
			(start -0.508 0.9398)
			(end 0.508 -0.9398)
			(stroke
				(width 0)
				(type default)
			)
			(fill no)
			(layer "F.Fab")
		)
		(pad "1" smd custom
			(at 0 -0.4445 180)
			(size 0.1397 0.1397)
			(layers "F.Cu" "F.Mask" "F.Paste")
			(net "DRIVE_A_20_ACT")
			(options
				(clearance outline)
				(anchor circle)
			)
			(primitives
				(gr_poly
					(pts
						(arc
							(start -0.1778 -0.2794)
							(mid -0.249642 -0.249642)
							(end -0.2794 -0.1778)
						)
						(arc
							(start -0.2794 0.1778)
							(mid -0.249642 0.249642)
							(end -0.1778 0.2794)
						)
						(arc
							(start 0.1778 0.2794)
							(mid 0.249642 0.249642)
							(end 0.2794 0.1778)
						)
						(arc
							(start 0.2794 -0.1778)
							(mid 0.249642 -0.249642)
							(end 0.1778 -0.2794)
						)
					)
					(width 0)
					(fill yes)
				)
			)
		)
		(pad "2" smd custom
			(at 0 0.4445 180)
			(size 0.1397 0.1397)
			(layers "F.Cu" "F.Mask" "F.Paste")
			(net "GND")
			(options
				(clearance outline)
				(anchor circle)
			)
			(primitives
				(gr_poly
					(pts
						(arc
							(start -0.1778 -0.2794)
							(mid -0.249642 -0.249642)
							(end -0.2794 -0.1778)
						)
						(arc
							(start -0.2794 0.1778)
							(mid -0.249642 0.249642)
							(end -0.1778 0.2794)
						)
						(arc
							(start 0.1778 0.2794)
							(mid 0.249642 0.249642)
							(end 0.2794 0.1778)
						)
						(arc
							(start 0.2794 -0.1778)
							(mid 0.249642 -0.249642)
							(end 0.1778 -0.2794)
						)
					)
					(width 0)
					(fill yes)
				)
			)
		)
	)
	(footprint ""
		(layer "F.Cu")
		(at 115.080796 -177.778918 -90)
		(property "Reference" "C235"
			(at 0 0 270)
			(layer "F.SilkS")
			(hide yes)
			(effects
				(font
					(size 1.27 1.27)
				)
			)
		)
		(property "Value" "SC1U16V3KX-5GP"
			(at 0 -2.8194 270)
			(unlocked yes)
			(layer "F.Fab")
			(hide yes)
			(effects
				(font
					(size 1.016 1.016)
					(thickness 0.1524)
				)
			)
		)
		(property "Device Type" "C603H36"
			(at 0 -4.3434 270)
			(unlocked yes)
			(layer "F.Fab")
			(hide yes)
			(effects
				(font
					(size 1.016 1.016)
					(thickness 0.1524)
				)
			)
		)
		(duplicate_pad_numbers_are_jumpers no)
		(fp_line
			(start 0.508 0)
			(end -0.508 0)
			(stroke
				(width 0.2032)
				(type default)
			)
			(layer "F.SilkS")
		)
		(fp_rect
			(start -0.5842 1.3335)
			(end 0.5842 -1.3335)
			(stroke
				(width 0)
				(type default)
			)
			(fill no)
			(layer "F.CrtYd")
		)
		(fp_rect
			(start -0.5842 1.3335)
			(end 0.5842 -1.3335)
			(stroke
				(width 0)
				(type default)
			)
			(fill no)
			(layer "F.Fab")
		)
		(pad "1" smd custom
			(at 0 -0.762 270)
			(size 0.2159 0.2159)
			(layers "F.Cu" "F.Mask" "F.Paste")
			(net "P5V_HDD15")
			(options
				(clearance outline)
				(anchor circle)
			)
			(primitives
				(gr_poly
					(pts
						(arc
							(start -0.3302 -0.4318)
							(mid -0.402042 -0.402042)
							(end -0.4318 -0.3302)
						)
						(arc
							(start -0.4318 0.3302)
							(mid -0.402042 0.402042)
							(end -0.3302 0.4318)
						)
						(arc
							(start 0.3302 0.4318)
							(mid 0.402042 0.402042)
							(end 0.4318 0.3302)
						)
						(arc
							(start 0.4318 -0.3302)
							(mid 0.402042 -0.402042)
							(end 0.3302 -0.4318)
						)
					)
					(width 0)
					(fill yes)
				)
			)
		)
		(pad "2" smd custom
			(at 0 0.762 270)
			(size 0.2159 0.2159)
			(layers "F.Cu" "F.Mask" "F.Paste")
			(net "GND")
			(options
				(clearance outline)
				(anchor circle)
			)
			(primitives
				(gr_poly
					(pts
						(arc
							(start -0.3302 -0.4318)
							(mid -0.402042 -0.402042)
							(end -0.4318 -0.3302)
						)
						(arc
							(start -0.4318 0.3302)
							(mid -0.402042 0.402042)
							(end -0.3302 0.4318)
						)
						(arc
							(start 0.3302 0.4318)
							(mid 0.402042 0.402042)
							(end 0.4318 0.3302)
						)
						(arc
							(start 0.4318 -0.3302)
							(mid 0.402042 -0.402042)
							(end 0.3302 -0.4318)
						)
					)
					(width 0)
					(fill yes)
				)
			)
		)
	)
	(footprint ""
		(layer "F.Cu")
		(at 324.739 -162.749992 -90)
		(property "Reference" "VIA28"
			(at 0 0 270)
			(layer "F.SilkS")
			(hide yes)
			(effects
				(font
					(size 1.27 1.27)
				)
			)
		)
		(property "Value" "100OHM-8L-1D6MM-L18L16-GP"
			(at -3.7211 -4.5085 270)
			(unlocked yes)
			(layer "F.Fab")
			(hide yes)
			(effects
				(font
					(size 1.016 1.016)
					(thickness 0.1524)
				)
			)
		)
		(property "Device Type" "VIA-PCIE-4P-394076"
			(at -3.7211 -6.0325 270)
			(unlocked yes)
			(layer "F.Fab")
			(hide yes)
			(effects
				(font
					(size 1.016 1.016)
					(thickness 0.1524)
				)
			)
		)
		(duplicate_pad_numbers_are_jumpers no)
		(fp_rect
			(start -1.9685 0.381)
			(end 1.9685 -0.381)
			(stroke
				(width 0)
				(type default)
			)
			(fill no)
			(layer "F.CrtYd")
		)
		(fp_rect
			(start -1.9685 0.381)
			(end 1.9685 -0.381)
			(stroke
				(width 0)
				(type default)
			)
			(fill no)
			(layer "F.Fab")
		)
		(pad "1" thru_hole circle
			(at -1.5875 0 270)
			(size 0.508 0.508)
			(drill 0.254)
			(layers "*.Cu" "*.Mask")
			(remove_unused_layers no)
			(net "GND")
			(clearance 0.127)
			(thermal_gap 0.127)
		)
		(pad "2" thru_hole circle
			(at -0.5715 0 270)
			(size 0.508 0.508)
			(drill 0.254)
			(layers "*.Cu" "*.Mask")
			(remove_unused_layers no)
			(net "PHY_DRV_A_TO_SCC_A_18_DP")
			(clearance 0.127)
			(thermal_gap 0.127)
		)
		(pad "3" thru_hole circle
			(at 0.5715 0 270)
			(size 0.508 0.508)
			(drill 0.254)
			(layers "*.Cu" "*.Mask")
			(remove_unused_layers no)
			(net "PHY_DRV_A_TO_SCC_A_18_DN")
			(clearance 0.127)
			(thermal_gap 0.127)
		)
		(pad "4" thru_hole circle
			(at 1.5875 0 270)
			(size 0.508 0.508)
			(drill 0.254)
			(layers "*.Cu" "*.Mask")
			(remove_unused_layers no)
			(net "GND")
			(clearance 0.127)
			(thermal_gap 0.127)
		)
	)
	(footprint ""
		(layer "F.Cu")
		(at 113.556796 -64.683894 90)
		(property "Reference" "R752"
			(at 0 0 90)
			(layer "F.SilkS")
			(hide yes)
			(effects
				(font
					(size 1.27 1.27)
				)
			)
		)
		(property "Value" "2R6F-GP"
			(at -0.0508 -4.8514 90)
			(unlocked yes)
			(layer "F.Fab")
			(hide yes)
			(effects
				(font
					(size 1.016 1.016)
					(thickness 0.1524)
				)
			)
		)
		(property "Device Type" "R1206H26"
			(at 0 -6.3754 90)
			(unlocked yes)
			(layer "F.Fab")
			(hide yes)
			(effects
				(font
					(size 1.016 1.016)
					(thickness 0.1524)
				)
			)
		)
		(duplicate_pad_numbers_are_jumpers no)
		(fp_line
			(start 1.016 -2.2352)
			(end 1.016 2.2352)
			(stroke
				(width 0.1524)
				(type default)
			)
			(layer "F.SilkS")
		)
		(fp_line
			(start -1.016 -2.2352)
			(end 1.016 -2.2352)
			(stroke
				(width 0.1524)
				(type default)
			)
			(layer "F.SilkS")
		)
		(fp_line
			(start 1.016 2.2352)
			(end -1.016 2.2352)
			(stroke
				(width 0.1524)
				(type default)
			)
			(layer "F.SilkS")
		)
		(fp_line
			(start -1.016 2.2352)
			(end -1.016 -2.2352)
			(stroke
				(width 0.1524)
				(type default)
			)
			(layer "F.SilkS")
		)
		(fp_rect
			(start -1.0922 2.3114)
			(end 1.0922 -2.3114)
			(stroke
				(width 0)
				(type default)
			)
			(fill no)
			(layer "F.CrtYd")
		)
		(fp_poly
			(pts
				(xy -1.0922 -2.3114) (xy 1.0922 -2.3114) (xy 1.0922 2.3114) (xy -1.0922 2.3114)
			)
			(stroke
				(width 0)
				(type default)
			)
			(fill no)
			(layer "F.Fab")
		)
		(pad "1" smd rect
			(at 0 -1.397 90)
			(size 1.651 1.27)
			(layers "F.Cu" "F.Mask" "F.Paste")
			(net "P12V_HDD27")
		)
		(pad "2" smd rect
			(at 0 1.397 90)
			(size 1.651 1.27)
			(layers "F.Cu" "F.Mask" "F.Paste")
			(net "12V_PRE_27")
		)
	)
	(footprint ""
		(layer "F.Cu")
		(at 264.301732 18.170144 -90)
		(property "Reference" "R136"
			(at 0 0 270)
			(layer "F.SilkS")
			(hide yes)
			(effects
				(font
					(size 1.27 1.27)
				)
			)
		)
		(property "Value" "4K7R2F-GP"
			(at 0.064008 -3.993896 270)
			(unlocked yes)
			(layer "F.Fab")
			(hide yes)
			(effects
				(font
					(size 1.016 1.016)
					(thickness 0.1524)
				)
			)
		)
		(property "Device Type" "R402H16"
			(at 0.064008 -5.517896 270)
			(unlocked yes)
			(layer "F.Fab")
			(hide yes)
			(effects
				(font
					(size 1.016 1.016)
					(thickness 0.1524)
				)
			)
		)
		(duplicate_pad_numbers_are_jumpers no)
		(fp_line
			(start -0.508 -0.9398)
			(end -0.508 0.9398)
			(stroke
				(width 0.1524)
				(type default)
			)
			(layer "F.SilkS")
		)
		(fp_line
			(start 0.508 -0.9398)
			(end -0.508 -0.9398)
			(stroke
				(width 0.1524)
				(type default)
			)
			(layer "F.SilkS")
		)
		(fp_rect
			(start -0.508 0.9398)
			(end 0.508 -0.9398)
			(stroke
				(width 0)
				(type default)
			)
			(fill no)
			(layer "F.CrtYd")
		)
		(fp_rect
			(start -0.508 0.9398)
			(end 0.508 -0.9398)
			(stroke
				(width 0)
				(type default)
			)
			(fill no)
			(layer "F.Fab")
		)
		(pad "1" smd custom
			(at 0 -0.4445 270)
			(size 0.1397 0.1397)
			(layers "F.Cu" "F.Mask" "F.Paste")
			(net "P5V_A_2")
			(options
				(clearance outline)
				(anchor circle)
			)
			(primitives
				(gr_poly
					(pts
						(arc
							(start -0.1778 -0.2794)
							(mid -0.249642 -0.249642)
							(end -0.2794 -0.1778)
						)
						(arc
							(start -0.2794 0.1778)
							(mid -0.249642 0.249642)
							(end -0.1778 0.2794)
						)
						(arc
							(start 0.1778 0.2794)
							(mid 0.249642 0.249642)
							(end 0.2794 0.1778)
						)
						(arc
							(start 0.2794 -0.1778)
							(mid 0.249642 -0.249642)
							(end 0.1778 -0.2794)
						)
					)
					(width 0)
					(fill yes)
				)
			)
		)
		(pad "2" smd custom
			(at 0 0.4445 270)
			(size 0.1397 0.1397)
			(layers "F.Cu" "F.Mask" "F.Paste")
			(net "USB_OCS_N1")
			(options
				(clearance outline)
				(anchor circle)
			)
			(primitives
				(gr_poly
					(pts
						(arc
							(start -0.1778 -0.2794)
							(mid -0.249642 -0.249642)
							(end -0.2794 -0.1778)
						)
						(arc
							(start -0.2794 0.1778)
							(mid -0.249642 0.249642)
							(end -0.1778 0.2794)
						)
						(arc
							(start 0.1778 0.2794)
							(mid 0.249642 0.249642)
							(end 0.2794 0.1778)
						)
						(arc
							(start 0.2794 -0.1778)
							(mid 0.249642 -0.249642)
							(end 0.1778 -0.2794)
						)
					)
					(width 0)
					(fill yes)
				)
			)
		)
	)
	(footprint ""
		(layer "F.Cu")
		(at 46.392846 -59.857894)
		(property "Reference" "Q152"
			(at 0 0 0)
			(layer "F.SilkS")
			(hide yes)
			(effects
				(font
					(size 1.27 1.27)
				)
			)
		)
		(property "Value" "AO4407AL-GP"
			(at -3.707384 -1.5367 0)
			(unlocked yes)
			(layer "F.Fab")
			(hide yes)
			(effects
				(font
					(size 1.016 1.016)
					(thickness 0.1524)
				)
			)
		)
		(property "Device Type" "SOIC8H69"
			(at -3.707384 -3.0607 0)
			(unlocked yes)
			(layer "F.Fab")
			(hide yes)
			(effects
				(font
					(size 1.016 1.016)
					(thickness 0.1524)
				)
			)
		)
		(duplicate_pad_numbers_are_jumpers no)
		(fp_line
			(start -2.7432 -1.4224)
			(end -2.7432 1.4224)
			(stroke
				(width 0.1524)
				(type default)
			)
			(layer "F.SilkS")
		)
		(fp_line
			(start -2.7432 1.4224)
			(end -2.6416 1.4224)
			(stroke
				(width 0.1524)
				(type default)
			)
			(layer "F.SilkS")
		)
		(fp_line
			(start -2.7432 1.4224)
			(end 2.1336 1.4224)
			(stroke
				(width 0.1524)
				(type default)
			)
			(layer "F.SilkS")
		)
		(fp_line
			(start -2.7178 -0.508)
			(end -2.1844 -0.0508)
			(stroke
				(width 0.1524)
				(type default)
			)
			(layer "F.SilkS")
		)
		(fp_line
			(start -2.6289 3.4417)
			(end -2.6289 1.4732)
			(stroke
				(width 0.381)
				(type default)
			)
			(layer "F.SilkS")
		)
		(fp_line
			(start -2.1844 -0.0508)
			(end -2.7178 0.508)
			(stroke
				(width 0.1524)
				(type default)
			)
			(layer "F.SilkS")
		)
		(fp_line
			(start 2.1336 -1.4224)
			(end -2.7432 -1.4224)
			(stroke
				(width 0.1524)
				(type default)
			)
			(layer "F.SilkS")
		)
		(fp_line
			(start 2.1336 1.4224)
			(end 2.1336 -1.4224)
			(stroke
				(width 0.1524)
				(type default)
			)
			(layer "F.SilkS")
		)
		(fp_poly
			(pts
				(xy -2.2098 -1.4224) (xy -2.2098 1.4224) (xy 2.2098 1.4224) (xy 2.2098 -1.4224)
			)
			(stroke
				(width 0)
				(type default)
			)
			(fill yes)
			(layer "F.SilkS")
		)
		(fp_rect
			(start -2.450084 2.999994)
			(end 2.450084 -2.999994)
			(stroke
				(width 0)
				(type default)
			)
			(fill no)
			(layer "F.CrtYd")
		)
		(fp_poly
			(pts
				(xy -2.8194 3.6322) (xy -2.8194 -3.6322) (xy 2.8194 -3.6322) (xy 2.8194 1.18364) (xy 2.450084 1.18364)
				(xy 2.450084 -2.999994) (xy -2.450084 -2.999994) (xy -2.450084 2.999994) (xy 2.450084 2.999994)
				(xy 2.450084 1.18618) (xy 2.8194 1.18618) (xy 2.8194 3.6322)
			)
			(stroke
				(width 0)
				(type default)
			)
			(fill no)
			(layer "F.CrtYd")
		)
		(fp_rect
			(start -2.8194 3.6322)
			(end 2.8194 -3.6322)
			(stroke
				(width 0)
				(type default)
			)
			(fill no)
			(layer "F.Fab")
		)
		(pad "1" smd rect
			(at -1.905 2.54)
			(size 0.635 1.651)
			(layers "F.Cu" "F.Mask" "F.Paste")
			(net "P12V_A")
		)
		(pad "2" smd rect
			(at -0.635 2.54)
			(size 0.635 1.651)
			(layers "F.Cu" "F.Mask" "F.Paste")
			(net "P12V_A")
		)
		(pad "3" smd rect
			(at 0.635 2.54)
			(size 0.635 1.651)
			(layers "F.Cu" "F.Mask" "F.Paste")
			(net "P12V_A")
		)
		(pad "4" smd rect
			(at 1.905 2.54)
			(size 0.635 1.651)
			(layers "F.Cu" "F.Mask" "F.Paste")
			(net "SW_HDD_N25")
		)
		(pad "5" smd rect
			(at 1.905 -2.54)
			(size 0.635 1.651)
			(layers "F.Cu" "F.Mask" "F.Paste")
			(net "P12V_HDD25")
		)
		(pad "6" smd rect
			(at 0.635 -2.54)
			(size 0.635 1.651)
			(layers "F.Cu" "F.Mask" "F.Paste")
			(net "P12V_HDD25")
		)
		(pad "7" smd rect
			(at -0.635 -2.54)
			(size 0.635 1.651)
			(layers "F.Cu" "F.Mask" "F.Paste")
			(net "P12V_HDD25")
		)
		(pad "8" smd rect
			(at -1.905 -2.54)
			(size 0.635 1.651)
			(layers "F.Cu" "F.Mask" "F.Paste")
			(net "P12V_HDD25")
		)
	)
)
